# BASEBOARD_FAB2 (Tioga Pass) — schematic netlist excerpt (pin names and nets, part order shuffled) for the footprints in the layout excerpt that follows; sources: Cadence DE-HDL packaged netlist, KiCad conversion of Wiwynn_Tioga_Pass_MB.brd

C8M10  CAP_A  47UF 4V 20% X5R  pkg 0603V  page 228 : A = PVDDQ_KLM ; B = GND
R1W1  1MR2F-L-GP  1%  pkg SMD-RG1  page 250 : \1\ = P3V3_STBY ; \2\ = FM_OCP_MEZZA_PRES_N
R2T16  RES  75 1.0% CHIP  pkg 0402  page 93 : A = H_CPU_ERR0_GTL_R_N ; B = H_CPU_ERR0_GTL_N

(kicad_pcb
	(version 20260206)
	(generator "pcbnew")
	(generator_version "10.0")
	(general
		(thickness 1.6)
		(legacy_teardrops no)
	)
	(paper "A4")
	(title_block
		(title "Wiwynn_Tioga_Pass_MB.brd")
		(comment 1 "Tioga Pass / footprints 4220-4222 of 4770")
	)
	(layers
		(0 "F.Cu" signal "TOP")
		(4 "In1.Cu" signal "L2GND")
		(6 "In2.Cu" signal "L3")
		(8 "In3.Cu" signal "L4GND")
		(10 "In4.Cu" signal "L5")
		(12 "In5.Cu" signal "L6GND")
		(14 "In6.Cu" signal "L7VCC")
		(16 "In7.Cu" signal "L8VCC")
		(18 "In8.Cu" signal "L9GND")
		(20 "In9.Cu" signal "L10")
		(22 "In10.Cu" signal "L11GND")
		(24 "In11.Cu" signal "L12")
		(26 "In12.Cu" signal "L13GND")
		(2 "B.Cu" signal "BOTTOM")
		(9 "F.Adhes" user "F.Adhesive")
		(11 "B.Adhes" user "B.Adhesive")
		(13 "F.Paste" user "Package Geometry/Pastemask Top")
		(15 "B.Paste" user "Package Geometry/Pastemask Bottom")
		(5 "F.SilkS" user "Ref Des/Silkscreen Top")
		(7 "B.SilkS" user "Ref Des/Silkscreen Bottom")
		(1 "F.Mask" user "Board Geometry/Soldermask Top")
		(3 "B.Mask" user "Board Geometry/Soldermask Bottom")
		(17 "Dwgs.User" user "User.Drawings")
		(19 "Cmts.User" user "User.Comments")
		(21 "Eco1.User" user "User.Eco1")
		(23 "Eco2.User" user "User.Eco2")
		(25 "Edge.Cuts" user "Board Geometry/Outline")
		(27 "Margin" user)
		(31 "F.CrtYd" user "Package Geometry/Place Bound Top")
		(29 "B.CrtYd" user "Package Geometry/Place Bound Bottom")
		(35 "F.Fab" user "Ref Des/Assembly Top")
		(33 "B.Fab" user "Ref Des/Assembly Bottom")
	)
	(footprint ""
		(layer "B.Cu")
		(at 80.81518 -125.64745 90)
		(property "Reference" "C8M10"
			(at -1.17602 3.79222 0)
			(unlocked yes)
			(layer "B.SilkS")
			(effects
				(font
					(size 0.7874 0.5842)
					(thickness 0.1524)
				)
				(justify mirror)
			)
		)
		(property "Value" ""
			(at 0 0 90)
			(layer "B.Fab")
			(effects
				(font
					(size 1.27 1.27)
				)
				(justify mirror)
			)
		)
		(duplicate_pad_numbers_are_jumpers no)
		(fp_rect
			(start 0.500126 1.598422)
			(end -0.500126 -0.201422)
			(stroke
				(width 0)
				(type default)
			)
			(fill no)
			(layer "B.CrtYd")
		)
		(fp_line
			(start 0.500126 -0.201422)
			(end -0.500126 -0.201422)
			(stroke
				(width 0.1)
				(type default)
			)
			(layer "B.Fab")
		)
		(fp_line
			(start -0.500126 -0.201422)
			(end -0.500126 1.598422)
			(stroke
				(width 0.1)
				(type default)
			)
			(layer "B.Fab")
		)
		(fp_line
			(start 0.500126 1.598422)
			(end 0.500126 -0.201422)
			(stroke
				(width 0.1)
				(type default)
			)
			(layer "B.Fab")
		)
		(fp_line
			(start -0.500126 1.598422)
			(end 0.500126 1.598422)
			(stroke
				(width 0.1)
				(type default)
			)
			(layer "B.Fab")
		)
		(pad "1" smd rect
			(at 0 0)
			(size 0.889 0.9906)
			(layers "B.Cu" "B.Mask" "B.Paste")
			(net "PVDDQ_KLM")
		)
		(pad "2" smd rect
			(at 0 1.397)
			(size 0.889 0.9906)
			(layers "B.Cu" "B.Mask" "B.Paste")
			(net "GND")
		)
		(zone
			(layer "B.Cu")
			(hatch none 0.5)
			(connect_pads
				(clearance 0)
			)
			(min_thickness 0.25)
			(keepout
				(tracks allowed)
				(vias not_allowed)
				(pads allowed)
				(copperpour not_allowed)
				(footprints allowed)
			)
			(placement
				(enabled no)
				(sheetname "")
			)
			(fill
				(thermal_gap 0.5)
				(thermal_bridge_width 0.5)
				(island_removal_mode 0)
			)
			(polygon
				(pts
					(xy 81.76768 -126.14275) (xy 81.25968 -126.14275) (xy 81.25968 -125.15215) (xy 81.76768 -125.15215)
				)
			)
		)
		(zone
			(layer "B.Cu")
			(hatch none 0.5)
			(connect_pads
				(clearance 0)
			)
			(min_thickness 0.25)
			(keepout
				(tracks not_allowed)
				(vias allowed)
				(pads allowed)
				(copperpour not_allowed)
				(footprints allowed)
			)
			(placement
				(enabled no)
				(sheetname "")
			)
			(fill
				(thermal_gap 0.5)
				(thermal_bridge_width 0.5)
				(island_removal_mode 0)
			)
			(polygon
				(pts
					(xy 81.76768 -126.14275) (xy 81.25968 -126.14275) (xy 81.25968 -125.15215) (xy 81.76768 -125.15215)
				)
			)
		)
	)
	(footprint ""
		(layer "B.Cu")
		(at 478.730564 -120.39473 -90)
		(property "Reference" "R1W1"
			(at 0 0 90)
			(layer "B.SilkS")
			(hide yes)
			(effects
				(font
					(size 1.27 1.27)
				)
				(justify mirror)
			)
		)
		(property "Value" "*"
			(at -0.064008 -4.108196 270)
			(unlocked yes)
			(layer "B.Fab")
			(hide yes)
			(effects
				(font
					(size 1.27 1.016)
					(thickness 0.1524)
				)
				(justify mirror)
			)
		)
		(property "Device Type" "1MR2F-L-GP_SMD-RG1-1MR2F-L-GP,A"
			(at -0.064008 -5.632196 270)
			(unlocked yes)
			(layer "B.Fab")
			(hide yes)
			(effects
				(font
					(size 1.27 1.016)
					(thickness 0.1524)
				)
				(justify mirror)
			)
		)
		(duplicate_pad_numbers_are_jumpers no)
		(fp_line
			(start -0.508 -0.9398)
			(end 0.508 -0.9398)
			(stroke
				(width 0.1524)
				(type default)
			)
			(layer "B.SilkS")
		)
		(fp_line
			(start 0.508 -0.9398)
			(end 0.508 0.9398)
			(stroke
				(width 0.1524)
				(type default)
			)
			(layer "B.SilkS")
		)
		(fp_rect
			(start 0.508 0.9398)
			(end -0.508 -0.9398)
			(stroke
				(width 0)
				(type default)
			)
			(fill no)
			(layer "B.CrtYd")
		)
		(fp_rect
			(start 0.508 0.9398)
			(end -0.508 -0.9398)
			(stroke
				(width 0)
				(type default)
			)
			(fill no)
			(layer "B.Fab")
		)
		(pad "1" smd custom
			(at 0 -0.4445 90)
			(size 0.1397 0.1397)
			(layers "B.Cu" "B.Mask" "B.Paste")
			(net "P3V3_STBY")
			(options
				(clearance outline)
				(anchor circle)
			)
			(primitives
				(gr_poly
					(pts
						(arc
							(start -0.1778 0.2794)
							(mid -0.249642 0.249642)
							(end -0.2794 0.1778)
						)
						(arc
							(start -0.2794 -0.1778)
							(mid -0.249642 -0.249642)
							(end -0.1778 -0.2794)
						)
						(arc
							(start 0.1778 -0.2794)
							(mid 0.249642 -0.249642)
							(end 0.2794 -0.1778)
						)
						(arc
							(start 0.2794 0.1778)
							(mid 0.249642 0.249642)
							(end 0.1778 0.2794)
						)
					)
					(width 0)
					(fill yes)
				)
			)
		)
		(pad "2" smd custom
			(at 0 0.4445 90)
			(size 0.1397 0.1397)
			(layers "B.Cu" "B.Mask" "B.Paste")
			(net "FM_OCP_MEZZA_PRES_N")
			(options
				(clearance outline)
				(anchor circle)
			)
			(primitives
				(gr_poly
					(pts
						(arc
							(start -0.1778 0.2794)
							(mid -0.249642 0.249642)
							(end -0.2794 0.1778)
						)
						(arc
							(start -0.2794 -0.1778)
							(mid -0.249642 -0.249642)
							(end -0.1778 -0.2794)
						)
						(arc
							(start 0.1778 -0.2794)
							(mid 0.249642 -0.249642)
							(end 0.2794 -0.1778)
						)
						(arc
							(start 0.2794 0.1778)
							(mid 0.249642 0.249642)
							(end 0.1778 0.2794)
						)
					)
					(width 0)
					(fill yes)
				)
			)
		)
	)
	(footprint ""
		(layer "B.Cu")
		(at 371.875558 -41.506648 -90)
		(property "Reference" "R2T16"
			(at 0 0 90)
			(layer "B.SilkS")
			(hide yes)
			(effects
				(font
					(size 1.27 1.27)
				)
				(justify mirror)
			)
		)
		(property "Value" ""
			(at 0 0 90)
			(layer "B.Fab")
			(effects
				(font
					(size 1.27 1.27)
				)
				(justify mirror)
			)
		)
		(duplicate_pad_numbers_are_jumpers no)
		(fp_poly
			(pts
				(xy 0.2794 -0.1016) (xy -0.2794 -0.1016) (xy -0.2794 0.9906) (xy 0.2794 0.9906)
			)
			(stroke
				(width 0)
				(type default)
			)
			(fill no)
			(layer "B.CrtYd")
		)
		(fp_line
			(start -0.2794 0.9906)
			(end -0.2794 -0.1016)
			(stroke
				(width 0.1)
				(type default)
			)
			(layer "B.Fab")
		)
		(fp_line
			(start 0.2794 0.9906)
			(end -0.2794 0.9906)
			(stroke
				(width 0.1)
				(type default)
			)
			(layer "B.Fab")
		)
		(fp_line
			(start -0.2794 -0.1016)
			(end 0.2794 -0.1016)
			(stroke
				(width 0.1)
				(type default)
			)
			(layer "B.Fab")
		)
		(fp_line
			(start 0.2794 -0.1016)
			(end 0.2794 0.9906)
			(stroke
				(width 0.1)
				(type default)
			)
			(layer "B.Fab")
		)
		(pad "1" smd rect
			(at 0 0 90)
			(size 0.508 0.508)
			(layers "B.Cu" "B.Mask" "B.Paste")
			(net "H_CPU_ERR0_GTL_R_N")
		)
		(pad "2" smd rect
			(at 0 0.889 90)
			(size 0.508 0.508)
			(layers "B.Cu" "B.Mask" "B.Paste")
			(net "H_CPU_ERR0_GTL_N")
		)
		(zone
			(layer "B.Cu")
			(hatch none 0.5)
			(connect_pads
				(clearance 0)
			)
			(min_thickness 0.25)
			(keepout
				(tracks not_allowed)
				(vias allowed)
				(pads allowed)
				(copperpour not_allowed)
				(footprints allowed)
			)
			(placement
				(enabled no)
				(sheetname "")
			)
			(fill
				(thermal_gap 0.5)
				(thermal_bridge_width 0.5)
				(island_removal_mode 0)
			)
			(polygon
				(pts
					(xy 371.240558 -41.252648) (xy 371.240558 -41.760648) (xy 371.621558 -41.760648) (xy 371.621558 -41.252648)
				)
			)
		)
		(zone
			(layer "B.Cu")
			(hatch none 0.5)
			(connect_pads
				(clearance 0)
			)
			(min_thickness 0.25)
			(keepout
				(tracks allowed)
				(vias not_allowed)
				(pads allowed)
				(copperpour not_allowed)
				(footprints allowed)
			)
			(placement
				(enabled no)
				(sheetname "")
			)
			(fill
				(thermal_gap 0.5)
				(thermal_bridge_width 0.5)
				(island_removal_mode 0)
			)
			(polygon
				(pts
					(xy 371.621558 -41.252648) (xy 371.621558 -41.760648) (xy 371.240558 -41.760648) (xy 371.240558 -41.252648)
				)
			)
		)
	)
)
